# BASEBOARD_FAB2 (Tioga Pass) — schematic netlist excerpt (pin names and nets, part order shuffled) for the footprints in the layout excerpt that follows; sources: Cadence DE-HDL packaged netlist, KiCad conversion of Wiwynn_Tioga_Pass_MB.brd

R2T6  RES  4.75K 1% CHIP  pkg 0402  page 154 : A = P3V3_STBY ; B = FM_BACKUP_BIOS_SEL_N

(kicad_pcb
	(version 20260206)
	(generator "pcbnew")
	(generator_version "10.0")
	(general
		(thickness 1.6)
		(legacy_teardrops no)
	)
	(paper "A4")
	(title_block
		(title "Wiwynn_Tioga_Pass_MB.brd")
		(comment 1 "Tioga Pass / footprints 3921-3921 of 4770")
	)
	(layers
		(0 "F.Cu" signal "TOP")
		(4 "In1.Cu" signal "L2GND")
		(6 "In2.Cu" signal "L3")
		(8 "In3.Cu" signal "L4GND")
		(10 "In4.Cu" signal "L5")
		(12 "In5.Cu" signal "L6GND")
		(14 "In6.Cu" signal "L7VCC")
		(16 "In7.Cu" signal "L8VCC")
		(18 "In8.Cu" signal "L9GND")
		(20 "In9.Cu" signal "L10")
		(22 "In10.Cu" signal "L11GND")
		(24 "In11.Cu" signal "L12")
		(26 "In12.Cu" signal "L13GND")
		(2 "B.Cu" signal "BOTTOM")
		(9 "F.Adhes" user "F.Adhesive")
		(11 "B.Adhes" user "B.Adhesive")
		(13 "F.Paste" user "Package Geometry/Pastemask Top")
		(15 "B.Paste" user "Package Geometry/Pastemask Bottom")
		(5 "F.SilkS" user "Ref Des/Silkscreen Top")
		(7 "B.SilkS" user "Ref Des/Silkscreen Bottom")
		(1 "F.Mask" user "Board Geometry/Soldermask Top")
		(3 "B.Mask" user "Board Geometry/Soldermask Bottom")
		(17 "Dwgs.User" user "User.Drawings")
		(19 "Cmts.User" user "User.Comments")
		(21 "Eco1.User" user "User.Eco1")
		(23 "Eco2.User" user "User.Eco2")
		(25 "Edge.Cuts" user "Board Geometry/Outline")
		(27 "Margin" user)
		(31 "F.CrtYd" user "Package Geometry/Place Bound Top")
		(29 "B.CrtYd" user "Package Geometry/Place Bound Bottom")
		(35 "F.Fab" user "Ref Des/Assembly Top")
		(33 "B.Fab" user "Ref Des/Assembly Bottom")
	)
	(footprint ""
		(layer "B.Cu")
		(at 389.255 -66.167 90)
		(property "Reference" "R2T6"
			(at 0 0 90)
			(layer "B.SilkS")
			(hide yes)
			(effects
				(font
					(size 1.27 1.27)
				)
				(justify mirror)
			)
		)
		(property "Value" ""
			(at 0 0 90)
			(layer "B.Fab")
			(effects
				(font
					(size 1.27 1.27)
				)
				(justify mirror)
			)
		)
		(duplicate_pad_numbers_are_jumpers no)
		(fp_poly
			(pts
				(xy 0.2794 -0.1016) (xy -0.2794 -0.1016) (xy -0.2794 0.9906) (xy 0.2794 0.9906)
			)
			(stroke
				(width 0)
				(type default)
			)
			(fill no)
			(layer "B.CrtYd")
		)
		(fp_line
			(start 0.2794 -0.1016)
			(end 0.2794 0.9906)
			(stroke
				(width 0.1)
				(type default)
			)
			(layer "B.Fab")
		)
		(fp_line
			(start -0.2794 -0.1016)
			(end 0.2794 -0.1016)
			(stroke
				(width 0.1)
				(type default)
			)
			(layer "B.Fab")
		)
		(fp_line
			(start 0.2794 0.9906)
			(end -0.2794 0.9906)
			(stroke
				(width 0.1)
				(type default)
			)
			(layer "B.Fab")
		)
		(fp_line
			(start -0.2794 0.9906)
			(end -0.2794 -0.1016)
			(stroke
				(width 0.1)
				(type default)
			)
			(layer "B.Fab")
		)
		(pad "1" smd rect
			(at 0 0 270)
			(size 0.508 0.508)
			(layers "B.Cu" "B.Mask" "B.Paste")
			(net "P3V3_STBY")
		)
		(pad "2" smd rect
			(at 0 0.889 270)
			(size 0.508 0.508)
			(layers "B.Cu" "B.Mask" "B.Paste")
			(net "FM_BACKUP_BIOS_SEL_N")
		)
		(zone
			(layer "B.Cu")
			(hatch none 0.5)
			(connect_pads
				(clearance 0)
			)
			(min_thickness 0.25)
			(keepout
				(tracks allowed)
				(vias not_allowed)
				(pads allowed)
				(copperpour not_allowed)
				(footprints allowed)
			)
			(placement
				(enabled no)
				(sheetname "")
			)
			(fill
				(thermal_gap 0.5)
				(thermal_bridge_width 0.5)
				(island_removal_mode 0)
			)
			(polygon
				(pts
					(xy 389.509 -66.421) (xy 389.509 -65.913) (xy 389.89 -65.913) (xy 389.89 -66.421)
				)
			)
		)
		(zone
			(layer "B.Cu")
			(hatch none 0.5)
			(connect_pads
				(clearance 0)
			)
			(min_thickness 0.25)
			(keepout
				(tracks not_allowed)
				(vias allowed)
				(pads allowed)
				(copperpour not_allowed)
				(footprints allowed)
			)
			(placement
				(enabled no)
				(sheetname "")
			)
			(fill
				(thermal_gap 0.5)
				(thermal_bridge_width 0.5)
				(island_removal_mode 0)
			)
			(polygon
				(pts
					(xy 389.89 -66.421) (xy 389.89 -65.913) (xy 389.509 -65.913) (xy 389.509 -66.421)
				)
			)
		)
	)
)
